FILE_TYPE = CONNECTIVITY;
{Allegro Design Entry HDL 16.6-p007 (v16-6-112F) 10/10/2012}
"PAGE_NUMBER" = 140;
0"NC";
1"P3V3_STBY\g";
2"GND\g";
3"GND\g";
4"GND\g";
5"PU_NV_HOLD_N";
6"SPI_NIC_MOSI";
7"PU_NV_WP_N";
8"SPI_NIC_MISO_R";
9"SPI_NIC_MISO";
10"SPI_NIC_SCLK";
11"SPI_NIC_CS_N";
%"M25PE16"
"1","(-2350,2700)","0","mstr_memory","I1";
;
CDS_SEC"1"
GROUP"NI_I210&RJ45"
PART_NUMBER"H77797-001"
MATERIAL"IC"
LOCATION"U9E1"
CDS_LIB"mstr_memory"
PACK_TYPE"SM"
CDS_LOCATION"U9E1"
ROOM"NIC_SPRV"
SEC"1"
SEC_TYPE"SM"
BOM_COST"NT_GBE_BASE";
"VSS"
$PN"4"4;
"W_N"
$PN"3"7;
"RESET_N"
$PN"7"5;
"VCC"
$PN"8"1;
"S_N"
$PN"1"11;
"C"
$PN"6"10;
"DQ0"
$PN"5"6;
"DQ1"
$PN"2"8;
%"RES"
"2","(-3200,3300)","0","mstr_discrete","I10";
;
CDS_SEC"1"
VALUE"3.32K"
WATTAGE"1/16W"
MATERIAL"CHIP"
PART_NUMBER"G21796-027"
PACK_TYPE"0402"
TOLERANCE"1%"
LOCATION"R1R9"
GROUP"NI_I210&RJ45"
CDS_LIB"mstr_discrete"
ROOM"NIC_SPRV"
SEC"1"
CDS_LOCATION"R1R9"
BOM_COST"NT_GBE_BASE"
SEC_TYPE"0402";
"A"
$PN"1"1;
"B"
$PN"2"5;
%"RES"
"2","(-3550,3300)","0","mstr_discrete","I11";
;
CDS_SEC"1"
GROUP"NI_I210&RJ45"
TOLERANCE"1%"
VALUE"3.32K"
LOCATION"R1R3"
WATTAGE"1/16W"
MATERIAL"CHIP"
PART_NUMBER"G21796-027"
PACK_TYPE"0402"
CDS_LIB"mstr_discrete"
CDS_LOCATION"R1R3"
ROOM"NIC_SPRV"
SEC_TYPE"0402"
BOM_COST"NT_GBE_BASE"
SEC"1";
"A"
$PN"1"1;
"B"
$PN"2"7;
%"RES"
"2","(-3950,3300)","0","mstr_discrete","I12";
;
CDS_SEC"1"
TOLERANCE"1%"
VALUE"20.0K"
LOCATION"R1R7"
PACK_TYPE"0402"
PART_NUMBER"G21796-040"
MATERIAL"CHIP"
WATTAGE"1/16W"
GROUP"NI_I210&RJ45"
CDS_LIB"mstr_discrete"
CDS_LOCATION"R1R7"
ROOM"NIC_SPRV"
SEC"1"
SEC_TYPE"0402"
BOM_COST"NT_GBE_BASE";
"A"
$PN"1"1;
"B"
$PN"2"6;
%"P3V3_STBY"
"1","(-3950,3625)","0","mstr_symbols","I13";
;
VOLTAGE"3.3V"
SIZE"1B"
CDS_LIB"mstr_symbols"
BODY_TYPE"PLUMBING"
HDL_POWER"P3V3_STBY";
"G\NAC"1;
%"RES"
"2","(-3825,2350)","0","mstr_discrete","I14";
;
CDS_SEC"1"
GROUP"NI_I210&RJ45"
LOCATION"R1R6"
VALUE"3.32K"
PACK_TYPE"0402"
PART_NUMBER"G21796-027"
TOLERANCE"1%"
MATERIAL"EMPTY"
WATTAGE"1/16W"
CDS_LIB"mstr_discrete"
CDS_LOCATION"R1R6"
ROOM"NIC_SPRV"
BOM_COST"NT_GBE_BASE"
SEC_TYPE"0402"
SEC"1";
"A"
$PN"1"6;
"B"
$PN"2"2;
%"GND"
"1","(-3825,2075)","0","mstr_symbols","I16";
;
VOLTAGE"0.0V"
SIZE"1B"
CDS_LIB"mstr_symbols"
BODY_TYPE"PLUMBING"
HDL_POWER"GND";
"A\NAC"2;
%"RES"
"1","(-1400,2750)","0","mstr_discrete","I17";
;
CDS_SEC"1"
MATERIAL"CHIP"
PART_NUMBER"G21796-074"
PACK_TYPE"0402"
GROUP"NI_I210&RJ45"
VALUE"33.2"
TOLERANCE"1%"
LOCATION"R9E6"
WATTAGE"1/16W"
CDS_LIB"mstr_discrete"
CDS_LOCATION"R9E6"
SEC_TYPE"0402"
BOM_COST"NT_GBE_BASE"
SEC"1"
ROOM"NIC_SPRV";
"B"
$PN"2"9;
"A"
$PN"1"8;
%"CAP_A"
"1","(-2475,3375)","0","dev_discrete","I3";
;
TOLERANCE"10%"
MATERIAL"X7R"
VOLTAGE"16V"
VALUE"0.1UF"
PACK_TYPE"0402V"
LOCATION"C1R25"
PART_NUMBER"A36096-030"
GROUP"NI_I210&RJ45"
CDS_LIB"dev_discrete"
ROOM"NIC_SPRV"
CDS_LOCATION"C1R25"
CDS_SEC"1"
SEC"1"
SEC_TYPE"0402V"
BOM_COST"NT_GBE_BASE";
"B"
$PN"2"3;
"A"
$PN"1"1;
%"GND"
"1","(-2475,3100)","0","mstr_symbols","I4";
;
VOLTAGE"0.0V"
SIZE"1B"
CDS_LIB"mstr_symbols"
BODY_TYPE"PLUMBING"
HDL_POWER"GND";
"A\NAC"3;
%"GND"
"1","(-1900,2175)","0","mstr_symbols","I9";
;
VOLTAGE"0.0V"
SIZE"1B"
CDS_LIB"mstr_symbols"
BODY_TYPE"PLUMBING"
HDL_POWER"GND";
"A\NAC"4;
END.
